(kicad_pcb
	(version 20260206)
	(generator "pcbnew")
	(generator_version "10.0")
	(general
		(thickness 1.6)
		(legacy_teardrops no)
	)
	(paper "A4")
	(title_block
		(title "04192023_DAF0TMB3IC0_F0TG_MB_C_brd_V02_OCP.brd")
		(comment 1 "Grand Teton / footprints 4003-4008 of 8354")
	)
	(layers
		(0 "F.Cu" signal "TOP")
		(4 "In1.Cu" signal "GND")
		(6 "In2.Cu" signal "IN1")
		(8 "In3.Cu" signal "GND1")
		(10 "In4.Cu" signal "IN2")
		(12 "In5.Cu" signal "GND2")
		(14 "In6.Cu" signal "IN3")
		(16 "In7.Cu" signal "GND3")
		(18 "In8.Cu" signal "VCC")
		(20 "In9.Cu" signal "VCC1")
		(22 "In10.Cu" signal "GND4")
		(24 "In11.Cu" signal "IN4")
		(26 "In12.Cu" signal "GND5")
		(28 "In13.Cu" signal "IN5")
		(30 "In14.Cu" signal "GND6")
		(32 "In15.Cu" signal "IN6")
		(34 "In16.Cu" signal "GND7")
		(2 "B.Cu" signal "BOTTOM")
		(9 "F.Adhes" user "F.Adhesive")
		(11 "B.Adhes" user "B.Adhesive")
		(13 "F.Paste" user "Package Geometry/Pastemask Top")
		(15 "B.Paste" user "Package Geometry/Pastemask Bottom")
		(5 "F.SilkS" user "Ref Des/Silkscreen Top")
		(7 "B.SilkS" user "Ref Des/Silkscreen Bottom")
		(1 "F.Mask" user "Board Geometry/Soldermask Top")
		(3 "B.Mask" user "Board Geometry/Soldermask Bottom")
		(17 "Dwgs.User" user "User.Drawings")
		(19 "Cmts.User" user "User.Comments")
		(21 "Eco1.User" user "User.Eco1")
		(23 "Eco2.User" user "User.Eco2")
		(25 "Edge.Cuts" user "Board Geometry/Outline")
		(27 "Margin" user)
		(31 "F.CrtYd" user "Package Geometry/Place Bound Top")
		(29 "B.CrtYd" user "Package Geometry/Place Bound Bottom")
		(35 "F.Fab" user "Ref Des/Assembly Top")
		(33 "B.Fab" user "Ref Des/Assembly Bottom")
	)
	(footprint ""
		(layer "F.Cu")
		(at 23.495 -431.9143 90)
		(property "Reference" "R2893"
			(at 0 0 90)
			(layer "F.SilkS")
			(hide yes)
			(effects
				(font
					(size 1.27 1.27)
				)
			)
		)
		(property "Value" ""
			(at 0 0 90)
			(layer "F.Fab")
			(effects
				(font
					(size 1.27 1.27)
				)
			)
		)
		(duplicate_pad_numbers_are_jumpers no)
		(fp_line
			(start 0.7874 -0.4064)
			(end 0.7874 0.4064)
			(stroke
				(width 0.1524)
				(type default)
			)
			(layer "F.SilkS")
		)
		(fp_line
			(start -0.7874 -0.4064)
			(end 0.7874 -0.4064)
			(stroke
				(width 0.1524)
				(type default)
			)
			(layer "F.SilkS")
		)
		(fp_line
			(start 0.7874 0.4064)
			(end -0.7874 0.4064)
			(stroke
				(width 0.1524)
				(type default)
			)
			(layer "F.SilkS")
		)
		(fp_line
			(start -0.7874 0.4064)
			(end -0.7874 -0.4064)
			(stroke
				(width 0.1524)
				(type default)
			)
			(layer "F.SilkS")
		)
		(fp_line
			(start -0.12065 -0.305054)
			(end -0.12065 -0.2794)
			(stroke
				(width 0.1)
				(type default)
			)
			(layer "F.Fab")
		)
		(fp_line
			(start -0.67945 -0.305054)
			(end -0.12065 -0.305054)
			(stroke
				(width 0.1)
				(type default)
			)
			(layer "F.Fab")
		)
		(fp_line
			(start 0.67945 -0.3048)
			(end 0.67945 0.3048)
			(stroke
				(width 0.1)
				(type default)
			)
			(layer "F.Fab")
		)
		(fp_line
			(start 0.12065 -0.3048)
			(end 0.67945 -0.3048)
			(stroke
				(width 0.1)
				(type default)
			)
			(layer "F.Fab")
		)
		(fp_line
			(start 0.12065 -0.2794)
			(end 0.12065 -0.3048)
			(stroke
				(width 0.1)
				(type default)
			)
			(layer "F.Fab")
		)
		(fp_line
			(start -0.12065 -0.2794)
			(end 0.12065 -0.2794)
			(stroke
				(width 0.1)
				(type default)
			)
			(layer "F.Fab")
		)
		(fp_line
			(start 0.120396 0.2794)
			(end -0.12065 0.2794)
			(stroke
				(width 0.1)
				(type default)
			)
			(layer "F.Fab")
		)
		(fp_line
			(start -0.12065 0.2794)
			(end -0.12065 0.3048)
			(stroke
				(width 0.1)
				(type default)
			)
			(layer "F.Fab")
		)
		(fp_line
			(start 0.67945 0.3048)
			(end 0.120396 0.3048)
			(stroke
				(width 0.1)
				(type default)
			)
			(layer "F.Fab")
		)
		(fp_line
			(start 0.120396 0.3048)
			(end 0.120396 0.2794)
			(stroke
				(width 0.1)
				(type default)
			)
			(layer "F.Fab")
		)
		(fp_line
			(start -0.12065 0.3048)
			(end -0.67945 0.3048)
			(stroke
				(width 0.1)
				(type default)
			)
			(layer "F.Fab")
		)
		(fp_line
			(start -0.67945 0.3048)
			(end -0.67945 -0.305054)
			(stroke
				(width 0.1)
				(type default)
			)
			(layer "F.Fab")
		)
		(pad "1" smd circle
			(at -0.40005 0 90)
			(size 0 0)
			(layers "F.Cu" "F.Mask" "F.Paste")
			(net "SMB_1_BMC_GPU_R_SCL")
		)
		(pad "2" smd circle
			(at 0.40005 0 90)
			(size 0 0)
			(layers "F.Cu" "F.Mask" "F.Paste")
			(net "SMB_1_BMC_GPU_BUF_R_SCL")
		)
	)
	(footprint ""
		(layer "F.Cu")
		(at 57.901078 -175.823626 90)
		(property "Reference" "PL27"
			(at -4.994656 0.152908 0)
			(unlocked yes)
			(layer "F.SilkS")
			(effects
				(font
					(size 0.7874 0.5842)
					(thickness 0.1524)
				)
				(justify left)
			)
		)
		(property "Value" ""
			(at 0 0 90)
			(layer "F.Fab")
			(effects
				(font
					(size 1.27 1.27)
				)
			)
		)
		(duplicate_pad_numbers_are_jumpers no)
		(fp_line
			(start 3.24993 -3.24993)
			(end 3.24993 -2.2352)
			(stroke
				(width 0.1524)
				(type default)
			)
			(layer "F.SilkS")
		)
		(fp_line
			(start -3.24993 -3.24993)
			(end 3.24993 -3.24993)
			(stroke
				(width 0.1524)
				(type default)
			)
			(layer "F.SilkS")
		)
		(fp_line
			(start -3.24993 -2.2352)
			(end -3.24993 -3.24993)
			(stroke
				(width 0.1524)
				(type default)
			)
			(layer "F.SilkS")
		)
		(fp_line
			(start 3.24993 2.2352)
			(end 3.24993 3.24993)
			(stroke
				(width 0.1524)
				(type default)
			)
			(layer "F.SilkS")
		)
		(fp_line
			(start 3.24993 3.24993)
			(end -3.24993 3.24993)
			(stroke
				(width 0.1524)
				(type default)
			)
			(layer "F.SilkS")
		)
		(fp_line
			(start -3.24993 3.24993)
			(end -3.24993 2.2352)
			(stroke
				(width 0.1524)
				(type default)
			)
			(layer "F.SilkS")
		)
		(fp_line
			(start 3.24993 -3.24993)
			(end 3.24993 3.24993)
			(stroke
				(width 0.1)
				(type default)
			)
			(layer "F.Fab")
		)
		(fp_line
			(start -3.24993 -3.24993)
			(end 3.24993 -3.24993)
			(stroke
				(width 0.1)
				(type default)
			)
			(layer "F.Fab")
		)
		(fp_line
			(start 3.24993 3.24993)
			(end -3.24993 3.24993)
			(stroke
				(width 0.1)
				(type default)
			)
			(layer "F.Fab")
		)
		(fp_line
			(start -3.24993 3.24993)
			(end -3.24993 -3.24993)
			(stroke
				(width 0.1)
				(type default)
			)
			(layer "F.Fab")
		)
		(pad "1" smd rect
			(at -2.29997 0 90)
			(size 2.0066 4.2164)
			(layers "F.Cu" "F.Mask" "F.Paste")
			(net "GND")
		)
		(pad "2" smd rect
			(at 2.29997 0 90)
			(size 2.0066 4.2164)
			(layers "F.Cu" "F.Mask" "F.Paste")
			(net "IND_CPU0_P1_CPL0")
		)
	)
	(footprint ""
		(layer "F.Cu")
		(at 60.127388 -32.287972 180)
		(property "Reference" "R3868"
			(at 0 0 180)
			(layer "F.SilkS")
			(hide yes)
			(effects
				(font
					(size 1.27 1.27)
				)
			)
		)
		(property "Value" ""
			(at 0 0 180)
			(layer "F.Fab")
			(effects
				(font
					(size 1.27 1.27)
				)
			)
		)
		(duplicate_pad_numbers_are_jumpers no)
		(fp_line
			(start 0.7874 0.4064)
			(end -0.7874 0.4064)
			(stroke
				(width 0.1524)
				(type default)
			)
			(layer "F.SilkS")
		)
		(fp_line
			(start 0.7874 -0.4064)
			(end 0.7874 0.4064)
			(stroke
				(width 0.1524)
				(type default)
			)
			(layer "F.SilkS")
		)
		(fp_line
			(start -0.7874 0.4064)
			(end -0.7874 -0.4064)
			(stroke
				(width 0.1524)
				(type default)
			)
			(layer "F.SilkS")
		)
		(fp_line
			(start -0.7874 -0.4064)
			(end 0.7874 -0.4064)
			(stroke
				(width 0.1524)
				(type default)
			)
			(layer "F.SilkS")
		)
		(fp_line
			(start 0.67945 0.3048)
			(end 0.120396 0.3048)
			(stroke
				(width 0.1)
				(type default)
			)
			(layer "F.Fab")
		)
		(fp_line
			(start 0.67945 -0.3048)
			(end 0.67945 0.3048)
			(stroke
				(width 0.1)
				(type default)
			)
			(layer "F.Fab")
		)
		(fp_line
			(start 0.12065 -0.2794)
			(end 0.12065 -0.3048)
			(stroke
				(width 0.1)
				(type default)
			)
			(layer "F.Fab")
		)
		(fp_line
			(start 0.12065 -0.3048)
			(end 0.67945 -0.3048)
			(stroke
				(width 0.1)
				(type default)
			)
			(layer "F.Fab")
		)
		(fp_line
			(start 0.120396 0.3048)
			(end 0.120396 0.2794)
			(stroke
				(width 0.1)
				(type default)
			)
			(layer "F.Fab")
		)
		(fp_line
			(start 0.120396 0.2794)
			(end -0.12065 0.2794)
			(stroke
				(width 0.1)
				(type default)
			)
			(layer "F.Fab")
		)
		(fp_line
			(start -0.12065 0.3048)
			(end -0.67945 0.3048)
			(stroke
				(width 0.1)
				(type default)
			)
			(layer "F.Fab")
		)
		(fp_line
			(start -0.12065 0.2794)
			(end -0.12065 0.3048)
			(stroke
				(width 0.1)
				(type default)
			)
			(layer "F.Fab")
		)
		(fp_line
			(start -0.12065 -0.2794)
			(end 0.12065 -0.2794)
			(stroke
				(width 0.1)
				(type default)
			)
			(layer "F.Fab")
		)
		(fp_line
			(start -0.12065 -0.305054)
			(end -0.12065 -0.2794)
			(stroke
				(width 0.1)
				(type default)
			)
			(layer "F.Fab")
		)
		(fp_line
			(start -0.67945 0.3048)
			(end -0.67945 -0.305054)
			(stroke
				(width 0.1)
				(type default)
			)
			(layer "F.Fab")
		)
		(fp_line
			(start -0.67945 -0.305054)
			(end -0.12065 -0.305054)
			(stroke
				(width 0.1)
				(type default)
			)
			(layer "F.Fab")
		)
		(pad "1" smd rect
			(at -0.40005 0)
			(size 0.4572 0.508)
			(layers "F.Cu" "F.Mask" "F.Paste")
			(net "P12V_OCP_SENSE_2")
		)
		(pad "2" smd rect
			(at 0.40005 0)
			(size 0.4572 0.508)
			(layers "F.Cu" "F.Mask" "F.Paste")
			(net "P12V_OCP_V3_2_ISENSE_MAM_TIC")
		)
	)
	(footprint ""
		(layer "F.Cu")
		(at 372.237 -424.053 90)
		(property "Reference" "R1216"
			(at 0 0 90)
			(layer "F.SilkS")
			(hide yes)
			(effects
				(font
					(size 1.27 1.27)
				)
			)
		)
		(property "Value" ""
			(at 0 0 90)
			(layer "F.Fab")
			(effects
				(font
					(size 1.27 1.27)
				)
			)
		)
		(duplicate_pad_numbers_are_jumpers no)
		(fp_line
			(start 0.32512 -0.175006)
			(end 0.32512 0.175006)
			(stroke
				(width 0.1)
				(type default)
			)
			(layer "F.Fab")
		)
		(fp_line
			(start -0.32512 -0.175006)
			(end 0.32512 -0.175006)
			(stroke
				(width 0.1)
				(type default)
			)
			(layer "F.Fab")
		)
		(fp_line
			(start 0.32512 0.175006)
			(end -0.32512 0.175006)
			(stroke
				(width 0.1)
				(type default)
			)
			(layer "F.Fab")
		)
		(fp_line
			(start -0.32512 0.175006)
			(end -0.32512 -0.175006)
			(stroke
				(width 0.1)
				(type default)
			)
			(layer "F.Fab")
		)
		(pad "1" smd rect
			(at -0.2667 0 90)
			(size 0.3048 0.381)
			(layers "F.Cu" "F.Mask" "F.Paste")
			(net "GND")
		)
		(pad "2" smd rect
			(at 0.2667 0 270)
			(size 0.3048 0.381)
			(layers "F.Cu" "F.Mask" "F.Paste")
			(net "RT_ROM_MUX7_OE_N")
		)
	)
	(footprint ""
		(layer "F.Cu")
		(at 455.01306 -37.295836)
		(property "Reference" "R1824"
			(at 0 0 0)
			(layer "F.SilkS")
			(hide yes)
			(effects
				(font
					(size 1.27 1.27)
				)
			)
		)
		(property "Value" ""
			(at 0 0 0)
			(layer "F.Fab")
			(effects
				(font
					(size 1.27 1.27)
				)
			)
		)
		(duplicate_pad_numbers_are_jumpers no)
		(fp_line
			(start -0.7874 -0.4064)
			(end 0.7874 -0.4064)
			(stroke
				(width 0.1524)
				(type default)
			)
			(layer "F.SilkS")
		)
		(fp_line
			(start -0.7874 0.4064)
			(end -0.7874 -0.4064)
			(stroke
				(width 0.1524)
				(type default)
			)
			(layer "F.SilkS")
		)
		(fp_line
			(start 0.7874 -0.4064)
			(end 0.7874 0.4064)
			(stroke
				(width 0.1524)
				(type default)
			)
			(layer "F.SilkS")
		)
		(fp_line
			(start 0.7874 0.4064)
			(end -0.7874 0.4064)
			(stroke
				(width 0.1524)
				(type default)
			)
			(layer "F.SilkS")
		)
		(fp_line
			(start -0.67945 -0.305054)
			(end -0.12065 -0.305054)
			(stroke
				(width 0.1)
				(type default)
			)
			(layer "F.Fab")
		)
		(fp_line
			(start -0.67945 0.3048)
			(end -0.67945 -0.305054)
			(stroke
				(width 0.1)
				(type default)
			)
			(layer "F.Fab")
		)
		(fp_line
			(start -0.12065 -0.305054)
			(end -0.12065 -0.2794)
			(stroke
				(width 0.1)
				(type default)
			)
			(layer "F.Fab")
		)
		(fp_line
			(start -0.12065 -0.2794)
			(end 0.12065 -0.2794)
			(stroke
				(width 0.1)
				(type default)
			)
			(layer "F.Fab")
		)
		(fp_line
			(start -0.12065 0.2794)
			(end -0.12065 0.3048)
			(stroke
				(width 0.1)
				(type default)
			)
			(layer "F.Fab")
		)
		(fp_line
			(start -0.12065 0.3048)
			(end -0.67945 0.3048)
			(stroke
				(width 0.1)
				(type default)
			)
			(layer "F.Fab")
		)
		(fp_line
			(start 0.120396 0.2794)
			(end -0.12065 0.2794)
			(stroke
				(width 0.1)
				(type default)
			)
			(layer "F.Fab")
		)
		(fp_line
			(start 0.120396 0.3048)
			(end 0.120396 0.2794)
			(stroke
				(width 0.1)
				(type default)
			)
			(layer "F.Fab")
		)
		(fp_line
			(start 0.12065 -0.3048)
			(end 0.67945 -0.3048)
			(stroke
				(width 0.1)
				(type default)
			)
			(layer "F.Fab")
		)
		(fp_line
			(start 0.12065 -0.2794)
			(end 0.12065 -0.3048)
			(stroke
				(width 0.1)
				(type default)
			)
			(layer "F.Fab")
		)
		(fp_line
			(start 0.67945 -0.3048)
			(end 0.67945 0.3048)
			(stroke
				(width 0.1)
				(type default)
			)
			(layer "F.Fab")
		)
		(fp_line
			(start 0.67945 0.3048)
			(end 0.120396 0.3048)
			(stroke
				(width 0.1)
				(type default)
			)
			(layer "F.Fab")
		)
		(pad "1" smd circle
			(at -0.40005 0)
			(size 0 0)
			(layers "F.Cu" "F.Mask" "F.Paste")
			(net "P3V3_OCP_SFF")
		)
		(pad "2" smd circle
			(at 0.40005 0)
			(size 0 0)
			(layers "F.Cu" "F.Mask" "F.Paste")
			(net "IRQ_LVC3_OCP_SFF_WAKE_N")
		)
	)
	(footprint ""
		(layer "F.Cu")
		(at 423.61866 -362.79963)
		(property "Reference" "PC193"
			(at 0 0 0)
			(layer "F.SilkS")
			(hide yes)
			(effects
				(font
					(size 1.27 1.27)
				)
			)
		)
		(property "Value" ""
			(at 0 0 0)
			(layer "F.Fab")
			(effects
				(font
					(size 1.27 1.27)
				)
			)
		)
		(duplicate_pad_numbers_are_jumpers no)
		(fp_line
			(start -0.7874 -0.4064)
			(end 0.7874 -0.4064)
			(stroke
				(width 0.1524)
				(type default)
			)
			(layer "F.SilkS")
		)
		(fp_line
			(start -0.7874 0.4064)
			(end -0.7874 -0.4064)
			(stroke
				(width 0.1524)
				(type default)
			)
			(layer "F.SilkS")
		)
		(fp_line
			(start 0.7874 -0.4064)
			(end 0.7874 0.4064)
			(stroke
				(width 0.1524)
				(type default)
			)
			(layer "F.SilkS")
		)
		(fp_line
			(start 0.7874 0.4064)
			(end -0.7874 0.4064)
			(stroke
				(width 0.1524)
				(type default)
			)
			(layer "F.SilkS")
		)
		(fp_line
			(start -0.67945 -0.305054)
			(end -0.12065 -0.305054)
			(stroke
				(width 0.1)
				(type default)
			)
			(layer "F.Fab")
		)
		(fp_line
			(start -0.67945 0.3048)
			(end -0.67945 -0.305054)
			(stroke
				(width 0.1)
				(type default)
			)
			(layer "F.Fab")
		)
		(fp_line
			(start -0.12065 -0.305054)
			(end -0.12065 -0.2794)
			(stroke
				(width 0.1)
				(type default)
			)
			(layer "F.Fab")
		)
		(fp_line
			(start -0.12065 -0.2794)
			(end 0.12065 -0.2794)
			(stroke
				(width 0.1)
				(type default)
			)
			(layer "F.Fab")
		)
		(fp_line
			(start -0.12065 0.2794)
			(end -0.12065 0.3048)
			(stroke
				(width 0.1)
				(type default)
			)
			(layer "F.Fab")
		)
		(fp_line
			(start -0.12065 0.3048)
			(end -0.67945 0.3048)
			(stroke
				(width 0.1)
				(type default)
			)
			(layer "F.Fab")
		)
		(fp_line
			(start 0.120396 0.2794)
			(end -0.12065 0.2794)
			(stroke
				(width 0.1)
				(type default)
			)
			(layer "F.Fab")
		)
		(fp_line
			(start 0.120396 0.3048)
			(end 0.120396 0.2794)
			(stroke
				(width 0.1)
				(type default)
			)
			(layer "F.Fab")
		)
		(fp_line
			(start 0.12065 -0.3048)
			(end 0.67945 -0.3048)
			(stroke
				(width 0.1)
				(type default)
			)
			(layer "F.Fab")
		)
		(fp_line
			(start 0.12065 -0.2794)
			(end 0.12065 -0.3048)
			(stroke
				(width 0.1)
				(type default)
			)
			(layer "F.Fab")
		)
		(fp_line
			(start 0.67945 -0.3048)
			(end 0.67945 0.3048)
			(stroke
				(width 0.1)
				(type default)
			)
			(layer "F.Fab")
		)
		(fp_line
			(start 0.67945 0.3048)
			(end 0.120396 0.3048)
			(stroke
				(width 0.1)
				(type default)
			)
			(layer "F.Fab")
		)
		(pad "1" smd circle
			(at -0.40005 0)
			(size 0 0)
			(layers "F.Cu" "F.Mask" "F.Paste")
			(net "PVDD11_S3_P0_VMON")
		)
		(pad "2" smd circle
			(at 0.40005 0)
			(size 0 0)
			(layers "F.Cu" "F.Mask" "F.Paste")
			(net "GND")
		)
	)
)
